# S9S_MB_2U (Grand Teton) — schematic netlist excerpt (pin names and nets, part order shuffled) for the footprints in the layout excerpt that follows; sources: Cadence DE-HDL packaged netlist, KiCad conversion of 03242023_DA0F0TMBIJ0_F0T_Motherboard_J_brd_V01_OCP.brd

R4737  Q_RES  10K 1% CHIP  pkg 0402LF  page 144 : A = P3V3_AUX ; B = PRSNT_CABLE_SWB_B1_N
R1792  Q_RES  0 5% EMPTY  pkg 0402LF  page 250 : A = SMB_VR_3V3AUX_SDA_R1 ; B = SMB_SEN_MAM_3V3AUX_SDA

U336  APX80929SAG7  APX809-29SAG-7 IC  pkg SOT23_123XI  page 191
  GND  = GND
  RESET_L  = HP_E1S_0_P3V3_PWRGD
  VCC  = P3V3_E1S_0

(kicad_pcb
	(version 20260206)
	(generator "pcbnew")
	(generator_version "10.0")
	(general
		(thickness 1.6)
		(legacy_teardrops no)
	)
	(paper "A4")
	(title_block
		(title "03242023_DA0F0TMBIJ0_F0T_Motherboard_J_brd_V01_OCP.brd")
		(comment 1 "Grand Teton / footprints 542-544 of 6105")
	)
	(layers
		(0 "F.Cu" signal "TOP")
		(4 "In1.Cu" signal "GND")
		(6 "In2.Cu" signal "IN1")
		(8 "In3.Cu" signal "GND1")
		(10 "In4.Cu" signal "IN2")
		(12 "In5.Cu" signal "GND2")
		(14 "In6.Cu" signal "IN3")
		(16 "In7.Cu" signal "GND3")
		(18 "In8.Cu" signal "VCC")
		(20 "In9.Cu" signal "VCC1")
		(22 "In10.Cu" signal "GND4")
		(24 "In11.Cu" signal "IN4")
		(26 "In12.Cu" signal "GND5")
		(28 "In13.Cu" signal "IN5")
		(30 "In14.Cu" signal "GND6")
		(32 "In15.Cu" signal "IN6")
		(34 "In16.Cu" signal "GND7")
		(2 "B.Cu" signal "BOTTOM")
		(9 "F.Adhes" user "F.Adhesive")
		(11 "B.Adhes" user "B.Adhesive")
		(13 "F.Paste" user "Package Geometry/Pastemask Top")
		(15 "B.Paste" user "Package Geometry/Pastemask Bottom")
		(5 "F.SilkS" user "Ref Des/Silkscreen Top")
		(7 "B.SilkS" user "Ref Des/Silkscreen Bottom")
		(1 "F.Mask" user "Board Geometry/Soldermask Top")
		(3 "B.Mask" user "Board Geometry/Soldermask Bottom")
		(17 "Dwgs.User" user "User.Drawings")
		(19 "Cmts.User" user "User.Comments")
		(21 "Eco1.User" user "User.Eco1")
		(23 "Eco2.User" user "User.Eco2")
		(25 "Edge.Cuts" user "Board Geometry/Outline")
		(27 "Margin" user)
		(31 "F.CrtYd" user "Package Geometry/Place Bound Top")
		(29 "B.CrtYd" user "Package Geometry/Place Bound Bottom")
		(35 "F.Fab" user "Ref Des/Assembly Top")
		(33 "B.Fab" user "Ref Des/Assembly Bottom")
	)
	(footprint ""
		(layer "F.Cu")
		(at 220.15704 -47.58436)
		(property "Reference" "U336"
			(at -0.79502 -3.38963 0)
			(unlocked yes)
			(layer "F.SilkS")
			(effects
				(font
					(size 0.7874 0.5842)
					(thickness 0.1524)
				)
				(justify left)
			)
		)
		(property "Value" ""
			(at 0 0 0)
			(layer "F.Fab")
			(effects
				(font
					(size 1.27 1.27)
				)
			)
		)
		(duplicate_pad_numbers_are_jumpers no)
		(fp_line
			(start -1.759712 -1.500124)
			(end 1.759712 -1.500124)
			(stroke
				(width 0.1524)
				(type default)
			)
			(layer "F.SilkS")
		)
		(fp_line
			(start -1.759712 1.500124)
			(end -1.759712 -1.500124)
			(stroke
				(width 0.1524)
				(type default)
			)
			(layer "F.SilkS")
		)
		(fp_line
			(start 1.759712 -1.500124)
			(end 1.759712 1.500124)
			(stroke
				(width 0.1524)
				(type default)
			)
			(layer "F.SilkS")
		)
		(fp_line
			(start 1.759712 1.500124)
			(end -1.759712 1.500124)
			(stroke
				(width 0.1524)
				(type default)
			)
			(layer "F.SilkS")
		)
		(fp_line
			(start -0.700024 -1.500124)
			(end 0.700024 -1.500124)
			(stroke
				(width 0.1)
				(type default)
			)
			(layer "F.Fab")
		)
		(fp_line
			(start -0.700024 1.500124)
			(end -0.700024 -1.500124)
			(stroke
				(width 0.1)
				(type default)
			)
			(layer "F.Fab")
		)
		(fp_line
			(start 0.700024 -1.500124)
			(end 0.700024 1.500124)
			(stroke
				(width 0.1)
				(type default)
			)
			(layer "F.Fab")
		)
		(fp_line
			(start 0.700024 1.500124)
			(end -0.700024 1.500124)
			(stroke
				(width 0.1)
				(type default)
			)
			(layer "F.Fab")
		)
		(pad "1" smd rect
			(at -1.150112 -0.94996 270)
			(size 0.6604 0.9652)
			(layers "F.Cu" "F.Mask" "F.Paste")
			(net "GND")
		)
		(pad "2" smd rect
			(at -1.150112 0.94996 270)
			(size 0.6604 0.9652)
			(layers "F.Cu" "F.Mask" "F.Paste")
			(net "HP_E1S_0_P3V3_PWRGD")
		)
		(pad "3" smd rect
			(at 1.150112 0 270)
			(size 0.6604 0.9652)
			(layers "F.Cu" "F.Mask" "F.Paste")
			(net "P3V3_E1S_0")
		)
	)
	(footprint ""
		(layer "F.Cu")
		(at 22.809454 -113.415826 180)
		(property "Reference" "R1792"
			(at 0 0 180)
			(layer "F.SilkS")
			(hide yes)
			(effects
				(font
					(size 1.27 1.27)
				)
			)
		)
		(property "Value" ""
			(at 0 0 180)
			(layer "F.Fab")
			(effects
				(font
					(size 1.27 1.27)
				)
			)
		)
		(duplicate_pad_numbers_are_jumpers no)
		(fp_line
			(start 0.7874 0.4064)
			(end -0.7874 0.4064)
			(stroke
				(width 0.1524)
				(type default)
			)
			(layer "F.SilkS")
		)
		(fp_line
			(start 0.7874 -0.4064)
			(end 0.7874 0.4064)
			(stroke
				(width 0.1524)
				(type default)
			)
			(layer "F.SilkS")
		)
		(fp_line
			(start -0.7874 0.4064)
			(end -0.7874 -0.4064)
			(stroke
				(width 0.1524)
				(type default)
			)
			(layer "F.SilkS")
		)
		(fp_line
			(start -0.7874 -0.4064)
			(end 0.7874 -0.4064)
			(stroke
				(width 0.1524)
				(type default)
			)
			(layer "F.SilkS")
		)
		(fp_line
			(start 0.67945 0.3048)
			(end 0.120396 0.3048)
			(stroke
				(width 0.1)
				(type default)
			)
			(layer "F.Fab")
		)
		(fp_line
			(start 0.67945 -0.3048)
			(end 0.67945 0.3048)
			(stroke
				(width 0.1)
				(type default)
			)
			(layer "F.Fab")
		)
		(fp_line
			(start 0.12065 -0.2794)
			(end 0.12065 -0.3048)
			(stroke
				(width 0.1)
				(type default)
			)
			(layer "F.Fab")
		)
		(fp_line
			(start 0.12065 -0.3048)
			(end 0.67945 -0.3048)
			(stroke
				(width 0.1)
				(type default)
			)
			(layer "F.Fab")
		)
		(fp_line
			(start 0.120396 0.3048)
			(end 0.120396 0.2794)
			(stroke
				(width 0.1)
				(type default)
			)
			(layer "F.Fab")
		)
		(fp_line
			(start 0.120396 0.2794)
			(end -0.12065 0.2794)
			(stroke
				(width 0.1)
				(type default)
			)
			(layer "F.Fab")
		)
		(fp_line
			(start -0.12065 0.3048)
			(end -0.67945 0.3048)
			(stroke
				(width 0.1)
				(type default)
			)
			(layer "F.Fab")
		)
		(fp_line
			(start -0.12065 0.2794)
			(end -0.12065 0.3048)
			(stroke
				(width 0.1)
				(type default)
			)
			(layer "F.Fab")
		)
		(fp_line
			(start -0.12065 -0.2794)
			(end 0.12065 -0.2794)
			(stroke
				(width 0.1)
				(type default)
			)
			(layer "F.Fab")
		)
		(fp_line
			(start -0.12065 -0.305054)
			(end -0.12065 -0.2794)
			(stroke
				(width 0.1)
				(type default)
			)
			(layer "F.Fab")
		)
		(fp_line
			(start -0.67945 0.3048)
			(end -0.67945 -0.305054)
			(stroke
				(width 0.1)
				(type default)
			)
			(layer "F.Fab")
		)
		(fp_line
			(start -0.67945 -0.305054)
			(end -0.12065 -0.305054)
			(stroke
				(width 0.1)
				(type default)
			)
			(layer "F.Fab")
		)
		(pad "1" smd circle
			(at -0.40005 0 180)
			(size 0 0)
			(layers "F.Cu" "F.Mask" "F.Paste")
			(net "SMB_VR_3V3AUX_SDA_R1")
		)
		(pad "2" smd circle
			(at 0.40005 0 180)
			(size 0 0)
			(layers "F.Cu" "F.Mask" "F.Paste")
			(net "SMB_SEN_MAM_3V3AUX_SDA")
		)
	)
	(footprint ""
		(layer "F.Cu")
		(at 366.3696 -408.1272)
		(property "Reference" "R4737"
			(at 0 0 0)
			(layer "F.SilkS")
			(hide yes)
			(effects
				(font
					(size 1.27 1.27)
				)
			)
		)
		(property "Value" ""
			(at 0 0 0)
			(layer "F.Fab")
			(effects
				(font
					(size 1.27 1.27)
				)
			)
		)
		(duplicate_pad_numbers_are_jumpers no)
		(fp_line
			(start -0.7874 -0.4064)
			(end 0.7874 -0.4064)
			(stroke
				(width 0.1524)
				(type default)
			)
			(layer "F.SilkS")
		)
		(fp_line
			(start -0.7874 0.4064)
			(end -0.7874 -0.4064)
			(stroke
				(width 0.1524)
				(type default)
			)
			(layer "F.SilkS")
		)
		(fp_line
			(start 0.7874 -0.4064)
			(end 0.7874 0.4064)
			(stroke
				(width 0.1524)
				(type default)
			)
			(layer "F.SilkS")
		)
		(fp_line
			(start 0.7874 0.4064)
			(end -0.7874 0.4064)
			(stroke
				(width 0.1524)
				(type default)
			)
			(layer "F.SilkS")
		)
		(fp_line
			(start -0.67945 -0.305054)
			(end -0.12065 -0.305054)
			(stroke
				(width 0.1)
				(type default)
			)
			(layer "F.Fab")
		)
		(fp_line
			(start -0.67945 0.3048)
			(end -0.67945 -0.305054)
			(stroke
				(width 0.1)
				(type default)
			)
			(layer "F.Fab")
		)
		(fp_line
			(start -0.12065 -0.305054)
			(end -0.12065 -0.2794)
			(stroke
				(width 0.1)
				(type default)
			)
			(layer "F.Fab")
		)
		(fp_line
			(start -0.12065 -0.2794)
			(end 0.12065 -0.2794)
			(stroke
				(width 0.1)
				(type default)
			)
			(layer "F.Fab")
		)
		(fp_line
			(start -0.12065 0.2794)
			(end -0.12065 0.3048)
			(stroke
				(width 0.1)
				(type default)
			)
			(layer "F.Fab")
		)
		(fp_line
			(start -0.12065 0.3048)
			(end -0.67945 0.3048)
			(stroke
				(width 0.1)
				(type default)
			)
			(layer "F.Fab")
		)
		(fp_line
			(start 0.120396 0.2794)
			(end -0.12065 0.2794)
			(stroke
				(width 0.1)
				(type default)
			)
			(layer "F.Fab")
		)
		(fp_line
			(start 0.120396 0.3048)
			(end 0.120396 0.2794)
			(stroke
				(width 0.1)
				(type default)
			)
			(layer "F.Fab")
		)
		(fp_line
			(start 0.12065 -0.3048)
			(end 0.67945 -0.3048)
			(stroke
				(width 0.1)
				(type default)
			)
			(layer "F.Fab")
		)
		(fp_line
			(start 0.12065 -0.2794)
			(end 0.12065 -0.3048)
			(stroke
				(width 0.1)
				(type default)
			)
			(layer "F.Fab")
		)
		(fp_line
			(start 0.67945 -0.3048)
			(end 0.67945 0.3048)
			(stroke
				(width 0.1)
				(type default)
			)
			(layer "F.Fab")
		)
		(fp_line
			(start 0.67945 0.3048)
			(end 0.120396 0.3048)
			(stroke
				(width 0.1)
				(type default)
			)
			(layer "F.Fab")
		)
		(pad "1" smd circle
			(at -0.40005 0)
			(size 0 0)
			(layers "F.Cu" "F.Mask" "F.Paste")
			(net "P3V3_AUX")
		)
		(pad "2" smd circle
			(at 0.40005 0)
			(size 0 0)
			(layers "F.Cu" "F.Mask" "F.Paste")
			(net "PRSNT_CABLE_SWB_B1_N")
		)
	)
)
